(kicad_pcb
	(version 20260206)
	(generator "pcbnew")
	(generator_version "10.0")
	(general
		(thickness 1.6)
		(legacy_teardrops no)
	)
	(paper "A4")
	(title_block
		(title "12092022_DA0F0TMDCD0_F0T_Management_Board_D_brd_V3_OCP.brd")
		(comment 1 "Grand Teton / footprints 616-621 of 1440")
	)
	(layers
		(0 "F.Cu" signal "TOP")
		(4 "In1.Cu" signal "GND")
		(6 "In2.Cu" signal "IN1")
		(8 "In3.Cu" signal "GND1")
		(10 "In4.Cu" signal "IN2")
		(12 "In5.Cu" signal "VCC")
		(14 "In6.Cu" signal "VCC1")
		(16 "In7.Cu" signal "IN3")
		(18 "In8.Cu" signal "GND2")
		(20 "In9.Cu" signal "IN4")
		(22 "In10.Cu" signal "GND3")
		(2 "B.Cu" signal "BOTTOM")
		(9 "F.Adhes" user "F.Adhesive")
		(11 "B.Adhes" user "B.Adhesive")
		(13 "F.Paste" user "Package Geometry/Pastemask Top")
		(15 "B.Paste" user "Package Geometry/Pastemask Bottom")
		(5 "F.SilkS" user "Ref Des/Silkscreen Top")
		(7 "B.SilkS" user "Ref Des/Silkscreen Bottom")
		(1 "F.Mask" user "Board Geometry/Soldermask Top")
		(3 "B.Mask" user "Board Geometry/Soldermask Bottom")
		(17 "Dwgs.User" user "User.Drawings")
		(19 "Cmts.User" user "User.Comments")
		(21 "Eco1.User" user "User.Eco1")
		(23 "Eco2.User" user "User.Eco2")
		(25 "Edge.Cuts" user "Board Geometry/Outline")
		(27 "Margin" user)
		(31 "F.CrtYd" user "Package Geometry/Place Bound Top")
		(29 "B.CrtYd" user "Package Geometry/Place Bound Bottom")
		(35 "F.Fab" user "Ref Des/Assembly Top")
		(33 "B.Fab" user "Ref Des/Assembly Bottom")
	)
	(footprint ""
		(layer "F.Cu")
		(at 12.065 -89.789 -90)
		(property "Reference" "R593"
			(at 0 0 270)
			(layer "F.SilkS")
			(hide yes)
			(effects
				(font
					(size 1.27 1.27)
				)
			)
		)
		(property "Value" ""
			(at 0 0 270)
			(layer "F.Fab")
			(effects
				(font
					(size 1.27 1.27)
				)
			)
		)
		(duplicate_pad_numbers_are_jumpers no)
		(fp_line
			(start -0.7874 0.4064)
			(end -0.7874 -0.4064)
			(stroke
				(width 0.1524)
				(type default)
			)
			(layer "F.SilkS")
		)
		(fp_line
			(start 0.7874 0.4064)
			(end -0.7874 0.4064)
			(stroke
				(width 0.1524)
				(type default)
			)
			(layer "F.SilkS")
		)
		(fp_line
			(start -0.7874 -0.4064)
			(end 0.7874 -0.4064)
			(stroke
				(width 0.1524)
				(type default)
			)
			(layer "F.SilkS")
		)
		(fp_line
			(start 0.7874 -0.4064)
			(end 0.7874 0.4064)
			(stroke
				(width 0.1524)
				(type default)
			)
			(layer "F.SilkS")
		)
		(fp_line
			(start -0.67945 0.3048)
			(end -0.67945 -0.305054)
			(stroke
				(width 0.1)
				(type default)
			)
			(layer "F.Fab")
		)
		(fp_line
			(start -0.12065 0.3048)
			(end -0.67945 0.3048)
			(stroke
				(width 0.1)
				(type default)
			)
			(layer "F.Fab")
		)
		(fp_line
			(start 0.120396 0.3048)
			(end 0.120396 0.2794)
			(stroke
				(width 0.1)
				(type default)
			)
			(layer "F.Fab")
		)
		(fp_line
			(start 0.67945 0.3048)
			(end 0.120396 0.3048)
			(stroke
				(width 0.1)
				(type default)
			)
			(layer "F.Fab")
		)
		(fp_line
			(start -0.12065 0.2794)
			(end -0.12065 0.3048)
			(stroke
				(width 0.1)
				(type default)
			)
			(layer "F.Fab")
		)
		(fp_line
			(start 0.120396 0.2794)
			(end -0.12065 0.2794)
			(stroke
				(width 0.1)
				(type default)
			)
			(layer "F.Fab")
		)
		(fp_line
			(start -0.12065 -0.2794)
			(end 0.12065 -0.2794)
			(stroke
				(width 0.1)
				(type default)
			)
			(layer "F.Fab")
		)
		(fp_line
			(start 0.12065 -0.2794)
			(end 0.12065 -0.3048)
			(stroke
				(width 0.1)
				(type default)
			)
			(layer "F.Fab")
		)
		(fp_line
			(start 0.12065 -0.3048)
			(end 0.67945 -0.3048)
			(stroke
				(width 0.1)
				(type default)
			)
			(layer "F.Fab")
		)
		(fp_line
			(start 0.67945 -0.3048)
			(end 0.67945 0.3048)
			(stroke
				(width 0.1)
				(type default)
			)
			(layer "F.Fab")
		)
		(fp_line
			(start -0.67945 -0.305054)
			(end -0.12065 -0.305054)
			(stroke
				(width 0.1)
				(type default)
			)
			(layer "F.Fab")
		)
		(fp_line
			(start -0.12065 -0.305054)
			(end -0.12065 -0.2794)
			(stroke
				(width 0.1)
				(type default)
			)
			(layer "F.Fab")
		)
		(pad "1" smd circle
			(at -0.40005 0 270)
			(size 0 0)
			(layers "F.Cu" "F.Mask" "F.Paste")
			(net "P3V3_AUX")
		)
		(pad "2" smd circle
			(at 0.40005 0 270)
			(size 0 0)
			(layers "F.Cu" "F.Mask" "F.Paste")
			(net "BMC_CPLD_GPIO_7")
		)
	)
	(footprint ""
		(layer "F.Cu")
		(at 75.946 -79.121 180)
		(property "Reference" "R631"
			(at 0 0 180)
			(layer "F.SilkS")
			(hide yes)
			(effects
				(font
					(size 1.27 1.27)
				)
			)
		)
		(property "Value" ""
			(at 0 0 180)
			(layer "F.Fab")
			(effects
				(font
					(size 1.27 1.27)
				)
			)
		)
		(duplicate_pad_numbers_are_jumpers no)
		(fp_line
			(start 0.7874 0.4064)
			(end -0.7874 0.4064)
			(stroke
				(width 0.1524)
				(type default)
			)
			(layer "F.SilkS")
		)
		(fp_line
			(start 0.7874 -0.4064)
			(end 0.7874 0.4064)
			(stroke
				(width 0.1524)
				(type default)
			)
			(layer "F.SilkS")
		)
		(fp_line
			(start -0.7874 0.4064)
			(end -0.7874 -0.4064)
			(stroke
				(width 0.1524)
				(type default)
			)
			(layer "F.SilkS")
		)
		(fp_line
			(start -0.7874 -0.4064)
			(end 0.7874 -0.4064)
			(stroke
				(width 0.1524)
				(type default)
			)
			(layer "F.SilkS")
		)
		(fp_line
			(start 0.67945 0.3048)
			(end 0.120396 0.3048)
			(stroke
				(width 0.1)
				(type default)
			)
			(layer "F.Fab")
		)
		(fp_line
			(start 0.67945 -0.3048)
			(end 0.67945 0.3048)
			(stroke
				(width 0.1)
				(type default)
			)
			(layer "F.Fab")
		)
		(fp_line
			(start 0.12065 -0.2794)
			(end 0.12065 -0.3048)
			(stroke
				(width 0.1)
				(type default)
			)
			(layer "F.Fab")
		)
		(fp_line
			(start 0.12065 -0.3048)
			(end 0.67945 -0.3048)
			(stroke
				(width 0.1)
				(type default)
			)
			(layer "F.Fab")
		)
		(fp_line
			(start 0.120396 0.3048)
			(end 0.120396 0.2794)
			(stroke
				(width 0.1)
				(type default)
			)
			(layer "F.Fab")
		)
		(fp_line
			(start 0.120396 0.2794)
			(end -0.12065 0.2794)
			(stroke
				(width 0.1)
				(type default)
			)
			(layer "F.Fab")
		)
		(fp_line
			(start -0.12065 0.3048)
			(end -0.67945 0.3048)
			(stroke
				(width 0.1)
				(type default)
			)
			(layer "F.Fab")
		)
		(fp_line
			(start -0.12065 0.2794)
			(end -0.12065 0.3048)
			(stroke
				(width 0.1)
				(type default)
			)
			(layer "F.Fab")
		)
		(fp_line
			(start -0.12065 -0.2794)
			(end 0.12065 -0.2794)
			(stroke
				(width 0.1)
				(type default)
			)
			(layer "F.Fab")
		)
		(fp_line
			(start -0.12065 -0.305054)
			(end -0.12065 -0.2794)
			(stroke
				(width 0.1)
				(type default)
			)
			(layer "F.Fab")
		)
		(fp_line
			(start -0.67945 0.3048)
			(end -0.67945 -0.305054)
			(stroke
				(width 0.1)
				(type default)
			)
			(layer "F.Fab")
		)
		(fp_line
			(start -0.67945 -0.305054)
			(end -0.12065 -0.305054)
			(stroke
				(width 0.1)
				(type default)
			)
			(layer "F.Fab")
		)
		(pad "1" smd circle
			(at -0.40005 0 180)
			(size 0 0)
			(layers "F.Cu" "F.Mask" "F.Paste")
			(net "P3V3_LDO")
		)
		(pad "2" smd circle
			(at 0.40005 0 180)
			(size 0 0)
			(layers "F.Cu" "F.Mask" "F.Paste")
			(net "U56_ADJ_1")
		)
	)
	(footprint ""
		(layer "F.Cu")
		(at 73.66 -94.6658)
		(property "Reference" "R113"
			(at 0 0 0)
			(layer "F.SilkS")
			(hide yes)
			(effects
				(font
					(size 1.27 1.27)
				)
			)
		)
		(property "Value" ""
			(at 0 0 0)
			(layer "F.Fab")
			(effects
				(font
					(size 1.27 1.27)
				)
			)
		)
		(duplicate_pad_numbers_are_jumpers no)
		(fp_line
			(start -0.7874 -0.4064)
			(end 0.7874 -0.4064)
			(stroke
				(width 0.1524)
				(type default)
			)
			(layer "F.SilkS")
		)
		(fp_line
			(start -0.7874 0.4064)
			(end -0.7874 -0.4064)
			(stroke
				(width 0.1524)
				(type default)
			)
			(layer "F.SilkS")
		)
		(fp_line
			(start 0.7874 -0.4064)
			(end 0.7874 0.4064)
			(stroke
				(width 0.1524)
				(type default)
			)
			(layer "F.SilkS")
		)
		(fp_line
			(start 0.7874 0.4064)
			(end -0.7874 0.4064)
			(stroke
				(width 0.1524)
				(type default)
			)
			(layer "F.SilkS")
		)
		(fp_line
			(start -0.67945 -0.305054)
			(end -0.12065 -0.305054)
			(stroke
				(width 0.1)
				(type default)
			)
			(layer "F.Fab")
		)
		(fp_line
			(start -0.67945 0.3048)
			(end -0.67945 -0.305054)
			(stroke
				(width 0.1)
				(type default)
			)
			(layer "F.Fab")
		)
		(fp_line
			(start -0.12065 -0.305054)
			(end -0.12065 -0.2794)
			(stroke
				(width 0.1)
				(type default)
			)
			(layer "F.Fab")
		)
		(fp_line
			(start -0.12065 -0.2794)
			(end 0.12065 -0.2794)
			(stroke
				(width 0.1)
				(type default)
			)
			(layer "F.Fab")
		)
		(fp_line
			(start -0.12065 0.2794)
			(end -0.12065 0.3048)
			(stroke
				(width 0.1)
				(type default)
			)
			(layer "F.Fab")
		)
		(fp_line
			(start -0.12065 0.3048)
			(end -0.67945 0.3048)
			(stroke
				(width 0.1)
				(type default)
			)
			(layer "F.Fab")
		)
		(fp_line
			(start 0.120396 0.2794)
			(end -0.12065 0.2794)
			(stroke
				(width 0.1)
				(type default)
			)
			(layer "F.Fab")
		)
		(fp_line
			(start 0.120396 0.3048)
			(end 0.120396 0.2794)
			(stroke
				(width 0.1)
				(type default)
			)
			(layer "F.Fab")
		)
		(fp_line
			(start 0.12065 -0.3048)
			(end 0.67945 -0.3048)
			(stroke
				(width 0.1)
				(type default)
			)
			(layer "F.Fab")
		)
		(fp_line
			(start 0.12065 -0.2794)
			(end 0.12065 -0.3048)
			(stroke
				(width 0.1)
				(type default)
			)
			(layer "F.Fab")
		)
		(fp_line
			(start 0.67945 -0.3048)
			(end 0.67945 0.3048)
			(stroke
				(width 0.1)
				(type default)
			)
			(layer "F.Fab")
		)
		(fp_line
			(start 0.67945 0.3048)
			(end 0.120396 0.3048)
			(stroke
				(width 0.1)
				(type default)
			)
			(layer "F.Fab")
		)
		(pad "1" smd circle
			(at -0.40005 0)
			(size 0 0)
			(layers "F.Cu" "F.Mask" "F.Paste")
			(net "IRQ_TPM_SPI_N")
		)
		(pad "2" smd circle
			(at 0.40005 0)
			(size 0 0)
			(layers "F.Cu" "F.Mask" "F.Paste")
			(net "IRQ_BMC_TPM_SPI_R_N")
		)
	)
	(footprint ""
		(layer "F.Cu")
		(at 6.4516 -107.3404)
		(property "Reference" "D20"
			(at -4.8641 -1.58623 0)
			(unlocked yes)
			(layer "F.SilkS")
			(effects
				(font
					(size 0.7874 0.5842)
					(thickness 0.1524)
				)
				(justify left)
			)
		)
		(property "Value" ""
			(at 0 0 0)
			(layer "F.Fab")
			(effects
				(font
					(size 1.27 1.27)
				)
			)
		)
		(duplicate_pad_numbers_are_jumpers no)
		(fp_line
			(start -2.4638 -1.0414)
			(end 2.7178 -1.0414)
			(stroke
				(width 0.1524)
				(type default)
			)
			(layer "F.SilkS")
		)
		(fp_line
			(start -2.4638 1.0414)
			(end -2.4638 -1.0414)
			(stroke
				(width 0.1524)
				(type default)
			)
			(layer "F.SilkS")
		)
		(fp_line
			(start -0.508 -0.508)
			(end -0.508 0.5334)
			(stroke
				(width 0.1524)
				(type default)
			)
			(layer "F.SilkS")
		)
		(fp_line
			(start -0.508 0.5334)
			(end 0.1778 -0.0254)
			(stroke
				(width 0.1524)
				(type default)
			)
			(layer "F.SilkS")
		)
		(fp_line
			(start 0.1778 -0.0254)
			(end -0.4826 -0.4826)
			(stroke
				(width 0.1524)
				(type default)
			)
			(layer "F.SilkS")
		)
		(fp_line
			(start 0.254 -0.508)
			(end 0.254 0.5334)
			(stroke
				(width 0.1524)
				(type default)
			)
			(layer "F.SilkS")
		)
		(fp_line
			(start 2.4638 -1.0414)
			(end 2.4638 1.0414)
			(stroke
				(width 0.1524)
				(type default)
			)
			(layer "F.SilkS")
		)
		(fp_line
			(start 2.5908 -1.0414)
			(end 2.5908 1.0414)
			(stroke
				(width 0.1524)
				(type default)
			)
			(layer "F.SilkS")
		)
		(fp_line
			(start 2.7178 -1.0414)
			(end 2.7178 1.0414)
			(stroke
				(width 0.1524)
				(type default)
			)
			(layer "F.SilkS")
		)
		(fp_line
			(start 2.7178 1.0414)
			(end -2.4638 1.0414)
			(stroke
				(width 0.1524)
				(type default)
			)
			(layer "F.SilkS")
		)
		(fp_line
			(start -2.4638 -1.0414)
			(end 2.7178 -1.0414)
			(stroke
				(width 0.1)
				(type default)
			)
			(layer "F.Fab")
		)
		(fp_line
			(start -2.4638 1.0414)
			(end -2.4638 -1.0414)
			(stroke
				(width 0.1)
				(type default)
			)
			(layer "F.Fab")
		)
		(fp_line
			(start 2.7178 -1.0414)
			(end 2.7178 1.0414)
			(stroke
				(width 0.1)
				(type default)
			)
			(layer "F.Fab")
		)
		(fp_line
			(start 2.7178 1.0414)
			(end -2.4638 1.0414)
			(stroke
				(width 0.1)
				(type default)
			)
			(layer "F.Fab")
		)
		(fp_text user "+"
			(at -3.9624 -0.17145 0)
			(unlocked yes)
			(layer "F.SilkS")
			(effects
				(font
					(size 1.905 1.4224)
					(thickness 0.1524)
				)
				(justify left)
			)
		)
		(fp_text user "-"
			(at 2.4892 -0.26035 0)
			(unlocked yes)
			(layer "F.SilkS")
			(effects
				(font
					(size 1.905 1.4224)
					(thickness 0.1524)
				)
				(justify left)
			)
		)
		(fp_text user "+"
			(at -3.9624 -0.17145 0)
			(unlocked yes)
			(layer "F.Fab")
			(effects
				(font
					(size 1.905 1.4224)
					(thickness 0.1524)
				)
				(justify left)
			)
		)
		(fp_text user "-"
			(at 2.9845 -0.366268 0)
			(unlocked yes)
			(layer "F.Fab")
			(effects
				(font
					(size 1.905 1.4224)
					(thickness 0.1524)
				)
				(justify left)
			)
		)
		(pad "1" smd rect
			(at -1.724914 0)
			(size 1.1684 1.7526)
			(layers "F.Cu" "F.Mask" "F.Paste")
			(net "P3V3_AUX")
		)
		(pad "2" smd rect
			(at 1.724914 0)
			(size 1.1684 1.7526)
			(layers "F.Cu" "F.Mask" "F.Paste")
			(net "J7_P1")
		)
	)
	(footprint ""
		(layer "F.Cu")
		(at 72.46493 -28.546044 90)
		(property "Reference" "R602"
			(at 0 0 90)
			(layer "F.SilkS")
			(hide yes)
			(effects
				(font
					(size 1.27 1.27)
				)
			)
		)
		(property "Value" ""
			(at 0 0 90)
			(layer "F.Fab")
			(effects
				(font
					(size 1.27 1.27)
				)
			)
		)
		(duplicate_pad_numbers_are_jumpers no)
		(fp_line
			(start 0.7874 -0.4064)
			(end 0.7874 0.4064)
			(stroke
				(width 0.1524)
				(type default)
			)
			(layer "F.SilkS")
		)
		(fp_line
			(start -0.7874 -0.4064)
			(end 0.7874 -0.4064)
			(stroke
				(width 0.1524)
				(type default)
			)
			(layer "F.SilkS")
		)
		(fp_line
			(start 0.7874 0.4064)
			(end -0.7874 0.4064)
			(stroke
				(width 0.1524)
				(type default)
			)
			(layer "F.SilkS")
		)
		(fp_line
			(start -0.7874 0.4064)
			(end -0.7874 -0.4064)
			(stroke
				(width 0.1524)
				(type default)
			)
			(layer "F.SilkS")
		)
		(fp_line
			(start -0.12065 -0.305054)
			(end -0.12065 -0.2794)
			(stroke
				(width 0.1)
				(type default)
			)
			(layer "F.Fab")
		)
		(fp_line
			(start -0.67945 -0.305054)
			(end -0.12065 -0.305054)
			(stroke
				(width 0.1)
				(type default)
			)
			(layer "F.Fab")
		)
		(fp_line
			(start 0.67945 -0.3048)
			(end 0.67945 0.3048)
			(stroke
				(width 0.1)
				(type default)
			)
			(layer "F.Fab")
		)
		(fp_line
			(start 0.12065 -0.3048)
			(end 0.67945 -0.3048)
			(stroke
				(width 0.1)
				(type default)
			)
			(layer "F.Fab")
		)
		(fp_line
			(start 0.12065 -0.2794)
			(end 0.12065 -0.3048)
			(stroke
				(width 0.1)
				(type default)
			)
			(layer "F.Fab")
		)
		(fp_line
			(start -0.12065 -0.2794)
			(end 0.12065 -0.2794)
			(stroke
				(width 0.1)
				(type default)
			)
			(layer "F.Fab")
		)
		(fp_line
			(start 0.120396 0.2794)
			(end -0.12065 0.2794)
			(stroke
				(width 0.1)
				(type default)
			)
			(layer "F.Fab")
		)
		(fp_line
			(start -0.12065 0.2794)
			(end -0.12065 0.3048)
			(stroke
				(width 0.1)
				(type default)
			)
			(layer "F.Fab")
		)
		(fp_line
			(start 0.67945 0.3048)
			(end 0.120396 0.3048)
			(stroke
				(width 0.1)
				(type default)
			)
			(layer "F.Fab")
		)
		(fp_line
			(start 0.120396 0.3048)
			(end 0.120396 0.2794)
			(stroke
				(width 0.1)
				(type default)
			)
			(layer "F.Fab")
		)
		(fp_line
			(start -0.12065 0.3048)
			(end -0.67945 0.3048)
			(stroke
				(width 0.1)
				(type default)
			)
			(layer "F.Fab")
		)
		(fp_line
			(start -0.67945 0.3048)
			(end -0.67945 -0.305054)
			(stroke
				(width 0.1)
				(type default)
			)
			(layer "F.Fab")
		)
		(pad "1" smd circle
			(at -0.40005 0 90)
			(size 0 0)
			(layers "F.Cu" "F.Mask" "F.Paste")
			(net "LED_POSTCODE_2")
		)
		(pad "2" smd circle
			(at 0.40005 0 90)
			(size 0 0)
			(layers "F.Cu" "F.Mask" "F.Paste")
			(net "LED_POSTCODE_2_R")
		)
	)
	(footprint ""
		(layer "F.Cu")
		(at 29.591 -10.287 -90)
		(property "Reference" "R815"
			(at 0 0 270)
			(layer "F.SilkS")
			(hide yes)
			(effects
				(font
					(size 1.27 1.27)
				)
			)
		)
		(property "Value" ""
			(at 0 0 270)
			(layer "F.Fab")
			(effects
				(font
					(size 1.27 1.27)
				)
			)
		)
		(duplicate_pad_numbers_are_jumpers no)
		(fp_line
			(start -0.7874 0.4064)
			(end -0.7874 -0.4064)
			(stroke
				(width 0.1524)
				(type default)
			)
			(layer "F.SilkS")
		)
		(fp_line
			(start 0.7874 0.4064)
			(end -0.7874 0.4064)
			(stroke
				(width 0.1524)
				(type default)
			)
			(layer "F.SilkS")
		)
		(fp_line
			(start -0.7874 -0.4064)
			(end 0.7874 -0.4064)
			(stroke
				(width 0.1524)
				(type default)
			)
			(layer "F.SilkS")
		)
		(fp_line
			(start 0.7874 -0.4064)
			(end 0.7874 0.4064)
			(stroke
				(width 0.1524)
				(type default)
			)
			(layer "F.SilkS")
		)
		(fp_line
			(start -0.67945 0.3048)
			(end -0.67945 -0.305054)
			(stroke
				(width 0.1)
				(type default)
			)
			(layer "F.Fab")
		)
		(fp_line
			(start -0.12065 0.3048)
			(end -0.67945 0.3048)
			(stroke
				(width 0.1)
				(type default)
			)
			(layer "F.Fab")
		)
		(fp_line
			(start 0.120396 0.3048)
			(end 0.120396 0.2794)
			(stroke
				(width 0.1)
				(type default)
			)
			(layer "F.Fab")
		)
		(fp_line
			(start 0.67945 0.3048)
			(end 0.120396 0.3048)
			(stroke
				(width 0.1)
				(type default)
			)
			(layer "F.Fab")
		)
		(fp_line
			(start -0.12065 0.2794)
			(end -0.12065 0.3048)
			(stroke
				(width 0.1)
				(type default)
			)
			(layer "F.Fab")
		)
		(fp_line
			(start 0.120396 0.2794)
			(end -0.12065 0.2794)
			(stroke
				(width 0.1)
				(type default)
			)
			(layer "F.Fab")
		)
		(fp_line
			(start -0.12065 -0.2794)
			(end 0.12065 -0.2794)
			(stroke
				(width 0.1)
				(type default)
			)
			(layer "F.Fab")
		)
		(fp_line
			(start 0.12065 -0.2794)
			(end 0.12065 -0.3048)
			(stroke
				(width 0.1)
				(type default)
			)
			(layer "F.Fab")
		)
		(fp_line
			(start 0.12065 -0.3048)
			(end 0.67945 -0.3048)
			(stroke
				(width 0.1)
				(type default)
			)
			(layer "F.Fab")
		)
		(fp_line
			(start 0.67945 -0.3048)
			(end 0.67945 0.3048)
			(stroke
				(width 0.1)
				(type default)
			)
			(layer "F.Fab")
		)
		(fp_line
			(start -0.67945 -0.305054)
			(end -0.12065 -0.305054)
			(stroke
				(width 0.1)
				(type default)
			)
			(layer "F.Fab")
		)
		(fp_line
			(start -0.12065 -0.305054)
			(end -0.12065 -0.2794)
			(stroke
				(width 0.1)
				(type default)
			)
			(layer "F.Fab")
		)
		(pad "1" smd circle
			(at -0.40005 0 270)
			(size 0 0)
			(layers "F.Cu" "F.Mask" "F.Paste")
			(net "P5V_AUX")
		)
		(pad "2" smd circle
			(at 0.40005 0 270)
			(size 0 0)
			(layers "F.Cu" "F.Mask" "F.Paste")
			(net "HDD_LED_BUF_R")
		)
	)
)
